# Stackup_F0T_PDB_Converter_10L_2p36mm_IT-170GT_RTF_Rev0p2_20211201.xls — Stackup (pcb-stackup)
| STACKUP |  |  |  | Target Z (ohms) - MicroStrip |  |  |  |  | 50 | Breakout |
|  |  |  |  | Target Z (ohms) - StripLine |  |  |  |  | 50 |  |
|  |  |  |  | Z tolerance |  |  |  |  | 0.1 |  |
|  |  |  |  | Z Type |  |  |  |  | Single | Single |
| Layer# | Material | Description |  | Copper Weight (oz) | Thickness (mil) | Tolerance (mil) | Glass Fabric | Er | Width | Width |
|  |  |  | Soldermask |  | 0.6 |  |  | 3.8 |  |  |
| 1 |  |  | TOP | 0.5+plating | 1.95 |  |  |  | 6.8 | 4 |
|  | IT-170GT |  | PP |  | 4 | ±0.709 | 106x2 | 3.87 |  |  |
| 2 |  |  | GND | 2 (RTF) | 2.6 |  |  |  |  |  |
|  | IT-170GT |  | CORE |  | 6 | ±0.984 | 1080x2 | 3.89 |  |  |
| 3 |  |  | IN1 | 1 (RTF) | 1.3 |  |  |  | 5.1 | 4 |
|  | IT-170GT |  | PP |  | 6 | ±0.984 | 3313x1+1078x1 | 3.89 |  |  |
| 4 |  |  | GND1 | 2 (RTF) | 2.6 |  |  |  |  |  |
|  | IT-170GT |  | CORE |  | 6 | ±0.984 | 1080x2 | 3.89 |  |  |
| 5 |  |  | VCC | 2 (RTF) | 2.6 |  |  |  |  |  |
|  | IT-170GT |  | PP |  | 25.6 | ±2.52 | Vendor Define | 4.08 |  |  |
| 6 |  |  | VCC1 | 2 (RTF) | 2.6 |  |  |  |  |  |
|  | IT-170GT |  | CORE |  | 6 | ±0.984 | 1080x2 | 3.89 |  |  |
| 7 |  |  | GND2 | 2 (RTF) | 2.6 |  |  |  |  |  |
|  | IT-170GT |  | PP |  | 6 | ±0.984 | 3313x1+1078x1 | 3.89 |  |  |
| 8 |  |  | IN2 | 1 (RTF) | 1.3 |  |  |  | 5.1 | 4 |
|  | IT-170GT |  | CORE |  | 6 | ±0.984 | 1080x2 | 3.89 |  |  |
| 9 |  |  | GND3 | 2 (RTF) | 2.6 |  |  |  |  |  |
|  | IT-170GT |  | PP |  | 4 | ±0.709 | 106x2 | 3.87 |  |  |
| 10 |  |  | BOTTOM | 0.5+plating | 1.95 |  |  |  | 6.8 | 4 |
|  |  |  | Soldermask |  | 0.6 |  |  | 3.8 |  |  |
|  |  |  |  | Total | 92.89999999999998 | ±10% |  |  |  |  |
